(kicad_pcb
	(version 20260206)
	(generator "pcbnew")
	(generator_version "10.0")
	(general
		(thickness 1.6)
		(legacy_teardrops no)
	)
	(paper "A4")
	(title_block
		(title "03242023_DA0F0TMBIJ0_F0T_Motherboard_J_brd_V01_OCP.brd")
		(comment 1 "Grand Teton / footprints 3901-3906 of 6105")
	)
	(layers
		(0 "F.Cu" signal "TOP")
		(4 "In1.Cu" signal "GND")
		(6 "In2.Cu" signal "IN1")
		(8 "In3.Cu" signal "GND1")
		(10 "In4.Cu" signal "IN2")
		(12 "In5.Cu" signal "GND2")
		(14 "In6.Cu" signal "IN3")
		(16 "In7.Cu" signal "GND3")
		(18 "In8.Cu" signal "VCC")
		(20 "In9.Cu" signal "VCC1")
		(22 "In10.Cu" signal "GND4")
		(24 "In11.Cu" signal "IN4")
		(26 "In12.Cu" signal "GND5")
		(28 "In13.Cu" signal "IN5")
		(30 "In14.Cu" signal "GND6")
		(32 "In15.Cu" signal "IN6")
		(34 "In16.Cu" signal "GND7")
		(2 "B.Cu" signal "BOTTOM")
		(9 "F.Adhes" user "F.Adhesive")
		(11 "B.Adhes" user "B.Adhesive")
		(13 "F.Paste" user "Package Geometry/Pastemask Top")
		(15 "B.Paste" user "Package Geometry/Pastemask Bottom")
		(5 "F.SilkS" user "Ref Des/Silkscreen Top")
		(7 "B.SilkS" user "Ref Des/Silkscreen Bottom")
		(1 "F.Mask" user "Board Geometry/Soldermask Top")
		(3 "B.Mask" user "Board Geometry/Soldermask Bottom")
		(17 "Dwgs.User" user "User.Drawings")
		(19 "Cmts.User" user "User.Comments")
		(21 "Eco1.User" user "User.Eco1")
		(23 "Eco2.User" user "User.Eco2")
		(25 "Edge.Cuts" user "Board Geometry/Outline")
		(27 "Margin" user)
		(31 "F.CrtYd" user "Package Geometry/Place Bound Top")
		(29 "B.CrtYd" user "Package Geometry/Place Bound Bottom")
		(35 "F.Fab" user "Ref Des/Assembly Top")
		(33 "B.Fab" user "Ref Des/Assembly Bottom")
	)
	(footprint ""
		(layer "F.Cu")
		(at 285.268162 -15.37843)
		(property "Reference" "R4179"
			(at 0 0 0)
			(layer "F.SilkS")
			(hide yes)
			(effects
				(font
					(size 1.27 1.27)
				)
			)
		)
		(property "Value" ""
			(at 0 0 0)
			(layer "F.Fab")
			(effects
				(font
					(size 1.27 1.27)
				)
			)
		)
		(duplicate_pad_numbers_are_jumpers no)
		(fp_line
			(start -0.7874 -0.4064)
			(end 0.7874 -0.4064)
			(stroke
				(width 0.1524)
				(type default)
			)
			(layer "F.SilkS")
		)
		(fp_line
			(start -0.7874 0.4064)
			(end -0.7874 -0.4064)
			(stroke
				(width 0.1524)
				(type default)
			)
			(layer "F.SilkS")
		)
		(fp_line
			(start 0.7874 -0.4064)
			(end 0.7874 0.4064)
			(stroke
				(width 0.1524)
				(type default)
			)
			(layer "F.SilkS")
		)
		(fp_line
			(start 0.7874 0.4064)
			(end -0.7874 0.4064)
			(stroke
				(width 0.1524)
				(type default)
			)
			(layer "F.SilkS")
		)
		(fp_line
			(start -0.67945 -0.305054)
			(end -0.12065 -0.305054)
			(stroke
				(width 0.1)
				(type default)
			)
			(layer "F.Fab")
		)
		(fp_line
			(start -0.67945 0.3048)
			(end -0.67945 -0.305054)
			(stroke
				(width 0.1)
				(type default)
			)
			(layer "F.Fab")
		)
		(fp_line
			(start -0.12065 -0.305054)
			(end -0.12065 -0.2794)
			(stroke
				(width 0.1)
				(type default)
			)
			(layer "F.Fab")
		)
		(fp_line
			(start -0.12065 -0.2794)
			(end 0.12065 -0.2794)
			(stroke
				(width 0.1)
				(type default)
			)
			(layer "F.Fab")
		)
		(fp_line
			(start -0.12065 0.2794)
			(end -0.12065 0.3048)
			(stroke
				(width 0.1)
				(type default)
			)
			(layer "F.Fab")
		)
		(fp_line
			(start -0.12065 0.3048)
			(end -0.67945 0.3048)
			(stroke
				(width 0.1)
				(type default)
			)
			(layer "F.Fab")
		)
		(fp_line
			(start 0.120396 0.2794)
			(end -0.12065 0.2794)
			(stroke
				(width 0.1)
				(type default)
			)
			(layer "F.Fab")
		)
		(fp_line
			(start 0.120396 0.3048)
			(end 0.120396 0.2794)
			(stroke
				(width 0.1)
				(type default)
			)
			(layer "F.Fab")
		)
		(fp_line
			(start 0.12065 -0.3048)
			(end 0.67945 -0.3048)
			(stroke
				(width 0.1)
				(type default)
			)
			(layer "F.Fab")
		)
		(fp_line
			(start 0.12065 -0.2794)
			(end 0.12065 -0.3048)
			(stroke
				(width 0.1)
				(type default)
			)
			(layer "F.Fab")
		)
		(fp_line
			(start 0.67945 -0.3048)
			(end 0.67945 0.3048)
			(stroke
				(width 0.1)
				(type default)
			)
			(layer "F.Fab")
		)
		(fp_line
			(start 0.67945 0.3048)
			(end 0.120396 0.3048)
			(stroke
				(width 0.1)
				(type default)
			)
			(layer "F.Fab")
		)
		(pad "1" smd circle
			(at -0.40005 0)
			(size 0 0)
			(layers "F.Cu" "F.Mask" "F.Paste")
			(net "SMB_LM75_1_3V3AUX_SCL")
		)
		(pad "2" smd circle
			(at 0.40005 0)
			(size 0 0)
			(layers "F.Cu" "F.Mask" "F.Paste")
			(net "SMB_LM75_1_3V3AUX_SCL_R1")
		)
	)
	(footprint ""
		(layer "F.Cu")
		(at 160.8328 -122.596148)
		(property "Reference" "R4625"
			(at 0 0 0)
			(layer "F.SilkS")
			(hide yes)
			(effects
				(font
					(size 1.27 1.27)
				)
			)
		)
		(property "Value" ""
			(at 0 0 0)
			(layer "F.Fab")
			(effects
				(font
					(size 1.27 1.27)
				)
			)
		)
		(duplicate_pad_numbers_are_jumpers no)
		(fp_line
			(start -0.7874 -0.4064)
			(end 0.7874 -0.4064)
			(stroke
				(width 0.1524)
				(type default)
			)
			(layer "F.SilkS")
		)
		(fp_line
			(start -0.7874 0.4064)
			(end -0.7874 -0.4064)
			(stroke
				(width 0.1524)
				(type default)
			)
			(layer "F.SilkS")
		)
		(fp_line
			(start 0.7874 -0.4064)
			(end 0.7874 0.4064)
			(stroke
				(width 0.1524)
				(type default)
			)
			(layer "F.SilkS")
		)
		(fp_line
			(start 0.7874 0.4064)
			(end -0.7874 0.4064)
			(stroke
				(width 0.1524)
				(type default)
			)
			(layer "F.SilkS")
		)
		(fp_line
			(start -0.67945 -0.305054)
			(end -0.12065 -0.305054)
			(stroke
				(width 0.1)
				(type default)
			)
			(layer "F.Fab")
		)
		(fp_line
			(start -0.67945 0.3048)
			(end -0.67945 -0.305054)
			(stroke
				(width 0.1)
				(type default)
			)
			(layer "F.Fab")
		)
		(fp_line
			(start -0.12065 -0.305054)
			(end -0.12065 -0.2794)
			(stroke
				(width 0.1)
				(type default)
			)
			(layer "F.Fab")
		)
		(fp_line
			(start -0.12065 -0.2794)
			(end 0.12065 -0.2794)
			(stroke
				(width 0.1)
				(type default)
			)
			(layer "F.Fab")
		)
		(fp_line
			(start -0.12065 0.2794)
			(end -0.12065 0.3048)
			(stroke
				(width 0.1)
				(type default)
			)
			(layer "F.Fab")
		)
		(fp_line
			(start -0.12065 0.3048)
			(end -0.67945 0.3048)
			(stroke
				(width 0.1)
				(type default)
			)
			(layer "F.Fab")
		)
		(fp_line
			(start 0.120396 0.2794)
			(end -0.12065 0.2794)
			(stroke
				(width 0.1)
				(type default)
			)
			(layer "F.Fab")
		)
		(fp_line
			(start 0.120396 0.3048)
			(end 0.120396 0.2794)
			(stroke
				(width 0.1)
				(type default)
			)
			(layer "F.Fab")
		)
		(fp_line
			(start 0.12065 -0.3048)
			(end 0.67945 -0.3048)
			(stroke
				(width 0.1)
				(type default)
			)
			(layer "F.Fab")
		)
		(fp_line
			(start 0.12065 -0.2794)
			(end 0.12065 -0.3048)
			(stroke
				(width 0.1)
				(type default)
			)
			(layer "F.Fab")
		)
		(fp_line
			(start 0.67945 -0.3048)
			(end 0.67945 0.3048)
			(stroke
				(width 0.1)
				(type default)
			)
			(layer "F.Fab")
		)
		(fp_line
			(start 0.67945 0.3048)
			(end 0.120396 0.3048)
			(stroke
				(width 0.1)
				(type default)
			)
			(layer "F.Fab")
		)
		(pad "1" smd circle
			(at -0.40005 0)
			(size 0 0)
			(layers "F.Cu" "F.Mask" "F.Paste")
			(net "JTAG_BMC_SW_OE")
		)
		(pad "2" smd circle
			(at 0.40005 0)
			(size 0 0)
			(layers "F.Cu" "F.Mask" "F.Paste")
			(net "JTAG_BMC_SW_PLD_OE")
		)
	)
	(footprint ""
		(layer "F.Cu")
		(at 106.328464 -238.162592 -90)
		(property "Reference" "C262"
			(at 0 0 270)
			(layer "F.SilkS")
			(hide yes)
			(effects
				(font
					(size 1.27 1.27)
				)
			)
		)
		(property "Value" ""
			(at 0 0 270)
			(layer "F.Fab")
			(effects
				(font
					(size 1.27 1.27)
				)
			)
		)
		(duplicate_pad_numbers_are_jumpers no)
		(fp_line
			(start -0.7874 0.4064)
			(end -0.7874 -0.4064)
			(stroke
				(width 0.1524)
				(type default)
			)
			(layer "F.SilkS")
		)
		(fp_line
			(start 0.7874 0.4064)
			(end -0.7874 0.4064)
			(stroke
				(width 0.1524)
				(type default)
			)
			(layer "F.SilkS")
		)
		(fp_line
			(start -0.7874 -0.4064)
			(end 0.7874 -0.4064)
			(stroke
				(width 0.1524)
				(type default)
			)
			(layer "F.SilkS")
		)
		(fp_line
			(start 0.7874 -0.4064)
			(end 0.7874 0.4064)
			(stroke
				(width 0.1524)
				(type default)
			)
			(layer "F.SilkS")
		)
		(fp_line
			(start -0.67945 0.3048)
			(end -0.67945 -0.305054)
			(stroke
				(width 0.1)
				(type default)
			)
			(layer "F.Fab")
		)
		(fp_line
			(start -0.12065 0.3048)
			(end -0.67945 0.3048)
			(stroke
				(width 0.1)
				(type default)
			)
			(layer "F.Fab")
		)
		(fp_line
			(start 0.120396 0.3048)
			(end 0.120396 0.2794)
			(stroke
				(width 0.1)
				(type default)
			)
			(layer "F.Fab")
		)
		(fp_line
			(start 0.67945 0.3048)
			(end 0.120396 0.3048)
			(stroke
				(width 0.1)
				(type default)
			)
			(layer "F.Fab")
		)
		(fp_line
			(start -0.12065 0.2794)
			(end -0.12065 0.3048)
			(stroke
				(width 0.1)
				(type default)
			)
			(layer "F.Fab")
		)
		(fp_line
			(start 0.120396 0.2794)
			(end -0.12065 0.2794)
			(stroke
				(width 0.1)
				(type default)
			)
			(layer "F.Fab")
		)
		(fp_line
			(start -0.12065 -0.2794)
			(end 0.12065 -0.2794)
			(stroke
				(width 0.1)
				(type default)
			)
			(layer "F.Fab")
		)
		(fp_line
			(start 0.12065 -0.2794)
			(end 0.12065 -0.3048)
			(stroke
				(width 0.1)
				(type default)
			)
			(layer "F.Fab")
		)
		(fp_line
			(start 0.12065 -0.3048)
			(end 0.67945 -0.3048)
			(stroke
				(width 0.1)
				(type default)
			)
			(layer "F.Fab")
		)
		(fp_line
			(start 0.67945 -0.3048)
			(end 0.67945 0.3048)
			(stroke
				(width 0.1)
				(type default)
			)
			(layer "F.Fab")
		)
		(fp_line
			(start -0.67945 -0.305054)
			(end -0.12065 -0.305054)
			(stroke
				(width 0.1)
				(type default)
			)
			(layer "F.Fab")
		)
		(fp_line
			(start -0.12065 -0.305054)
			(end -0.12065 -0.2794)
			(stroke
				(width 0.1)
				(type default)
			)
			(layer "F.Fab")
		)
		(pad "1" smd circle
			(at -0.40005 0 270)
			(size 0 0)
			(layers "F.Cu" "F.Mask" "F.Paste")
			(net "PVCCIN_CPU1")
		)
		(pad "2" smd circle
			(at 0.40005 0 270)
			(size 0 0)
			(layers "F.Cu" "F.Mask" "F.Paste")
			(net "GND")
		)
	)
	(footprint ""
		(layer "F.Cu")
		(at 254 -37.667946 180)
		(property "Reference" "R3976"
			(at 0 0 180)
			(layer "F.SilkS")
			(hide yes)
			(effects
				(font
					(size 1.27 1.27)
				)
			)
		)
		(property "Value" ""
			(at 0 0 180)
			(layer "F.Fab")
			(effects
				(font
					(size 1.27 1.27)
				)
			)
		)
		(duplicate_pad_numbers_are_jumpers no)
		(fp_line
			(start 0.7874 0.4064)
			(end -0.7874 0.4064)
			(stroke
				(width 0.1524)
				(type default)
			)
			(layer "F.SilkS")
		)
		(fp_line
			(start 0.7874 -0.4064)
			(end 0.7874 0.4064)
			(stroke
				(width 0.1524)
				(type default)
			)
			(layer "F.SilkS")
		)
		(fp_line
			(start -0.7874 0.4064)
			(end -0.7874 -0.4064)
			(stroke
				(width 0.1524)
				(type default)
			)
			(layer "F.SilkS")
		)
		(fp_line
			(start -0.7874 -0.4064)
			(end 0.7874 -0.4064)
			(stroke
				(width 0.1524)
				(type default)
			)
			(layer "F.SilkS")
		)
		(fp_line
			(start 0.67945 0.3048)
			(end 0.120396 0.3048)
			(stroke
				(width 0.1)
				(type default)
			)
			(layer "F.Fab")
		)
		(fp_line
			(start 0.67945 -0.3048)
			(end 0.67945 0.3048)
			(stroke
				(width 0.1)
				(type default)
			)
			(layer "F.Fab")
		)
		(fp_line
			(start 0.12065 -0.2794)
			(end 0.12065 -0.3048)
			(stroke
				(width 0.1)
				(type default)
			)
			(layer "F.Fab")
		)
		(fp_line
			(start 0.12065 -0.3048)
			(end 0.67945 -0.3048)
			(stroke
				(width 0.1)
				(type default)
			)
			(layer "F.Fab")
		)
		(fp_line
			(start 0.120396 0.3048)
			(end 0.120396 0.2794)
			(stroke
				(width 0.1)
				(type default)
			)
			(layer "F.Fab")
		)
		(fp_line
			(start 0.120396 0.2794)
			(end -0.12065 0.2794)
			(stroke
				(width 0.1)
				(type default)
			)
			(layer "F.Fab")
		)
		(fp_line
			(start -0.12065 0.3048)
			(end -0.67945 0.3048)
			(stroke
				(width 0.1)
				(type default)
			)
			(layer "F.Fab")
		)
		(fp_line
			(start -0.12065 0.2794)
			(end -0.12065 0.3048)
			(stroke
				(width 0.1)
				(type default)
			)
			(layer "F.Fab")
		)
		(fp_line
			(start -0.12065 -0.2794)
			(end 0.12065 -0.2794)
			(stroke
				(width 0.1)
				(type default)
			)
			(layer "F.Fab")
		)
		(fp_line
			(start -0.12065 -0.305054)
			(end -0.12065 -0.2794)
			(stroke
				(width 0.1)
				(type default)
			)
			(layer "F.Fab")
		)
		(fp_line
			(start -0.67945 0.3048)
			(end -0.67945 -0.305054)
			(stroke
				(width 0.1)
				(type default)
			)
			(layer "F.Fab")
		)
		(fp_line
			(start -0.67945 -0.305054)
			(end -0.12065 -0.305054)
			(stroke
				(width 0.1)
				(type default)
			)
			(layer "F.Fab")
		)
		(pad "1" smd circle
			(at -0.40005 0 180)
			(size 0 0)
			(layers "F.Cu" "F.Mask" "F.Paste")
			(net "P3V3_AUX")
		)
		(pad "2" smd circle
			(at 0.40005 0 180)
			(size 0 0)
			(layers "F.Cu" "F.Mask" "F.Paste")
			(net "P12V_E1S_FAULT_0")
		)
	)
	(footprint ""
		(layer "F.Cu")
		(at 462.078832 -360.76382)
		(property "Reference" "H127"
			(at -3.766312 -6.887718 0)
			(unlocked yes)
			(layer "F.SilkS")
			(effects
				(font
					(size 0.7874 0.5842)
					(thickness 0.1524)
				)
				(justify left)
			)
		)
		(property "Value" ""
			(at 0 0 0)
			(layer "F.Fab")
			(effects
				(font
					(size 1.27 1.27)
				)
			)
		)
		(duplicate_pad_numbers_are_jumpers no)
		(fp_arc
			(start 4.69773 3.430016)
			(mid -5.81025 -0.291475)
			(end 5.017516 -2.942082)
			(stroke
				(width 0.1524)
				(type default)
			)
			(layer "F.SilkS")
		)
		(fp_arc
			(start 4.7879 3.303016)
			(mid -5.810958 -0.220995)
			(end 5.025136 -2.929128)
			(stroke
				(width 0.1524)
				(type default)
			)
			(layer "B.SilkS")
		)
		(fp_circle
			(center 0 0)
			(end 5.8166 0)
			(stroke
				(width 0.1)
				(type default)
			)
			(fill no)
			(layer "B.Fab")
		)
		(fp_circle
			(center 0 0)
			(end 5.8166 0)
			(stroke
				(width 0.1)
				(type default)
			)
			(fill no)
			(layer "F.Fab")
		)
		(pad "" np_thru_hole circle
			(at 0 0)
			(size 10.0076 10.0076)
			(drill 10.0076)
			(layers "*.Cu" "*.Mask")
			(clearance 0.381)
			(thermal_gap 0.381)
		)
		(zone
			(layers "F.Cu" "B.Cu" "In1.Cu" "In2.Cu" "In3.Cu" "In4.Cu" "In5.Cu" "In6.Cu"
				"In7.Cu" "In8.Cu" "In9.Cu" "In10.Cu" "In11.Cu" "In12.Cu" "In13.Cu" "In14.Cu"
				"In15.Cu" "In16.Cu"
			)
			(hatch none 0.5)
			(connect_pads
				(clearance 0)
			)
			(min_thickness 0.25)
			(keepout
				(tracks not_allowed)
				(vias allowed)
				(pads allowed)
				(copperpour not_allowed)
				(footprints allowed)
			)
			(placement
				(enabled no)
				(sheetname "")
			)
			(fill
				(thermal_gap 0.5)
				(thermal_bridge_width 0.5)
				(island_removal_mode 0)
			)
			(polygon
				(pts
					(arc
						(start 467.590632 -360.76382)
						(mid 456.567032 -360.76382)
						(end 467.590632 -360.76382)
					)
				)
			)
		)
	)
	(footprint ""
		(layer "F.Cu")
		(at 179.760626 -421.729154 -90)
		(property "Reference" "U192"
			(at 6.665214 1.705864 90)
			(unlocked yes)
			(layer "F.SilkS")
			(effects
				(font
					(size 0.7874 0.5842)
					(thickness 0.1524)
				)
				(justify left)
			)
		)
		(property "Value" ""
			(at 0 0 270)
			(layer "F.Fab")
			(effects
				(font
					(size 1.27 1.27)
				)
			)
		)
		(duplicate_pad_numbers_are_jumpers no)
		(fp_line
			(start -1.3716 1.524)
			(end -1.3716 -1.524)
			(stroke
				(width 0.1524)
				(type default)
			)
			(layer "F.SilkS")
		)
		(fp_line
			(start 1.3716 1.524)
			(end -1.3716 1.524)
			(stroke
				(width 0.1524)
				(type default)
			)
			(layer "F.SilkS")
		)
		(fp_line
			(start 0 -1.016)
			(end 0.508 -1.524)
			(stroke
				(width 0.1524)
				(type default)
			)
			(layer "F.SilkS")
		)
		(fp_line
			(start -1.3716 -1.524)
			(end -0.508 -1.524)
			(stroke
				(width 0.1524)
				(type default)
			)
			(layer "F.SilkS")
		)
		(fp_line
			(start -0.508 -1.524)
			(end 0 -1.016)
			(stroke
				(width 0.1524)
				(type default)
			)
			(layer "F.SilkS")
		)
		(fp_line
			(start 0.508 -1.524)
			(end 1.3716 -1.524)
			(stroke
				(width 0.1524)
				(type default)
			)
			(layer "F.SilkS")
		)
		(fp_line
			(start 1.3716 -1.524)
			(end 1.3716 1.524)
			(stroke
				(width 0.1524)
				(type default)
			)
			(layer "F.SilkS")
		)
		(fp_poly
			(pts
				(xy -1.8669 -1.852676) (xy -2.195068 -1.298956) (xy -2.49174 -1.852676)
			)
			(stroke
				(width 0)
				(type default)
			)
			(fill yes)
			(layer "F.SilkS")
		)
		(fp_line
			(start -1.5494 1.524)
			(end -1.5494 1.0668)
			(stroke
				(width 0.1)
				(type default)
			)
			(layer "F.Fab")
		)
		(fp_line
			(start 1.5494 1.524)
			(end -1.5494 1.524)
			(stroke
				(width 0.1)
				(type default)
			)
			(layer "F.Fab")
		)
		(fp_line
			(start -2.54 1.0668)
			(end -2.54 -1.0668)
			(stroke
				(width 0.1)
				(type default)
			)
			(layer "F.Fab")
		)
		(fp_line
			(start -1.5494 1.0668)
			(end -2.54 1.0668)
			(stroke
				(width 0.1)
				(type default)
			)
			(layer "F.Fab")
		)
		(fp_line
			(start -1.5494 1.0668)
			(end -1.5494 -1.0668)
			(stroke
				(width 0.1)
				(type default)
			)
			(layer "F.Fab")
		)
		(fp_line
			(start 1.5494 1.0668)
			(end 1.5494 1.524)
			(stroke
				(width 0.1)
				(type default)
			)
			(layer "F.Fab")
		)
		(fp_line
			(start 2.54 1.0668)
			(end 1.5494 1.0668)
			(stroke
				(width 0.1)
				(type default)
			)
			(layer "F.Fab")
		)
		(fp_line
			(start -2.54 -1.0668)
			(end -1.5494 -1.0668)
			(stroke
				(width 0.1)
				(type default)
			)
			(layer "F.Fab")
		)
		(fp_line
			(start -1.5494 -1.0668)
			(end -1.5494 -1.524)
			(stroke
				(width 0.1)
				(type default)
			)
			(layer "F.Fab")
		)
		(fp_line
			(start 1.5494 -1.0668)
			(end 1.5494 1.0668)
			(stroke
				(width 0.1)
				(type default)
			)
			(layer "F.Fab")
		)
		(fp_line
			(start 1.5494 -1.0668)
			(end 2.54 -1.0668)
			(stroke
				(width 0.1)
				(type default)
			)
			(layer "F.Fab")
		)
		(fp_line
			(start 2.54 -1.0668)
			(end 2.54 1.0668)
			(stroke
				(width 0.1)
				(type default)
			)
			(layer "F.Fab")
		)
		(fp_line
			(start -1.5494 -1.524)
			(end 1.5494 -1.524)
			(stroke
				(width 0.1)
				(type default)
			)
			(layer "F.Fab")
		)
		(fp_line
			(start 1.5494 -1.524)
			(end 1.5494 -1.0668)
			(stroke
				(width 0.1)
				(type default)
			)
			(layer "F.Fab")
		)
		(fp_poly
			(pts
				(xy -3.60172 -0.719328) (xy -3.60172 -1.344168) (xy -3.048 -1.016)
			)
			(stroke
				(width 0)
				(type default)
			)
			(fill yes)
			(layer "F.Fab")
		)
		(pad "1" smd rect
			(at -2.232406 -0.975106 180)
			(size 0.3556 1.4224)
			(layers "F.Cu" "F.Mask" "F.Paste")
			(net "FM_MB_PDB_SMB9_R_EN")
		)
		(pad "2" smd rect
			(at -2.232406 -0.32512 180)
			(size 0.3556 1.4224)
			(layers "F.Cu" "F.Mask" "F.Paste")
			(net "SMB_FAN_3V3AUX_BUF_SCL")
		)
		(pad "3" smd rect
			(at -2.232406 0.32512 180)
			(size 0.3556 1.4224)
			(layers "F.Cu" "F.Mask" "F.Paste")
			(net "SMB_FAN_3V3AUX_R_SCL")
		)
		(pad "4" smd rect
			(at -2.232406 0.975106 180)
			(size 0.3556 1.4224)
			(layers "F.Cu" "F.Mask" "F.Paste")
			(net "GND")
		)
		(pad "5" smd rect
			(at 2.232406 0.975106 180)
			(size 0.3556 1.4224)
			(layers "F.Cu" "F.Mask" "F.Paste")
			(net "Net_1935")
		)
		(pad "6" smd rect
			(at 2.232406 0.32512 180)
			(size 0.3556 1.4224)
			(layers "F.Cu" "F.Mask" "F.Paste")
			(net "SMB_FAN_3V3AUX_R_SDA")
		)
		(pad "7" smd rect
			(at 2.232406 -0.32512 180)
			(size 0.3556 1.4224)
			(layers "F.Cu" "F.Mask" "F.Paste")
			(net "SMB_FAN_3V3AUX_BUF_SDA")
		)
		(pad "8" smd rect
			(at 2.232406 -0.975106 180)
			(size 0.3556 1.4224)
			(layers "F.Cu" "F.Mask" "F.Paste")
			(net "P3V3_AUX")
		)
	)
)
